(kicad_pcb
	(version 20260206)
	(generator "pcbnew")
	(generator_version "10.0")
	(general
		(thickness 1.6)
		(legacy_teardrops no)
	)
	(paper "A4")
	(title_block
		(title "m-2 — Lightning_M.2_BRD.brd")
		(comment 1 "Lightning (Wiwynn / Facebook NVMe JBOF) / footprints 100-106 of 157")
	)
	(layers
		(0 "F.Cu" signal "TOP")
		(4 "In1.Cu" signal "L2GND")
		(6 "In2.Cu" signal "L3")
		(8 "In3.Cu" signal "L4GND")
		(10 "In4.Cu" signal "L5GND")
		(12 "In5.Cu" signal "L6")
		(14 "In6.Cu" signal "L7GND")
		(2 "B.Cu" signal "BOTTOM")
		(9 "F.Adhes" user "F.Adhesive")
		(11 "B.Adhes" user "B.Adhesive")
		(13 "F.Paste" user "Package Geometry/Pastemask Top")
		(15 "B.Paste" user "Package Geometry/Pastemask Bottom")
		(5 "F.SilkS" user "Ref Des/Silkscreen Top")
		(7 "B.SilkS" user "Ref Des/Silkscreen Bottom")
		(1 "F.Mask" user "Board Geometry/Soldermask Top")
		(3 "B.Mask" user "Board Geometry/Soldermask Bottom")
		(17 "Dwgs.User" user "User.Drawings")
		(19 "Cmts.User" user "User.Comments")
		(21 "Eco1.User" user "User.Eco1")
		(23 "Eco2.User" user "User.Eco2")
		(25 "Edge.Cuts" user "Board Geometry/Outline")
		(27 "Margin" user)
		(31 "F.CrtYd" user "Package Geometry/Place Bound Top")
		(29 "B.CrtYd" user "Package Geometry/Place Bound Bottom")
		(35 "F.Fab" user "Ref Des/Assembly Top")
		(33 "B.Fab" user "Ref Des/Assembly Bottom")
	)
	(footprint ""
		(layer "B.Cu")
		(at 30.861 -86.233 180)
		(property "Reference" "R59"
			(at 0 0 0)
			(layer "B.SilkS")
			(hide yes)
			(effects
				(font
					(size 1.27 1.27)
				)
				(justify mirror)
			)
		)
		(property "Value" "47KR2F-GP"
			(at -0.064008 -3.993896 180)
			(unlocked yes)
			(layer "B.Fab")
			(hide yes)
			(effects
				(font
					(size 1.016 1.016)
					(thickness 0.1524)
				)
				(justify mirror)
			)
		)
		(property "Device Type" "R402H16"
			(at -0.064008 -5.517896 180)
			(unlocked yes)
			(layer "B.Fab")
			(hide yes)
			(effects
				(font
					(size 1.016 1.016)
					(thickness 0.1524)
				)
				(justify mirror)
			)
		)
		(duplicate_pad_numbers_are_jumpers no)
		(fp_line
			(start 0.508 -0.9398)
			(end 0.508 0.9398)
			(stroke
				(width 0.1524)
				(type default)
			)
			(layer "B.SilkS")
		)
		(fp_line
			(start -0.508 -0.9398)
			(end 0.508 -0.9398)
			(stroke
				(width 0.1524)
				(type default)
			)
			(layer "B.SilkS")
		)
		(fp_rect
			(start 0.508 0.9398)
			(end -0.508 -0.9398)
			(stroke
				(width 0)
				(type default)
			)
			(fill no)
			(layer "B.CrtYd")
		)
		(fp_rect
			(start 0.508 0.9398)
			(end -0.508 -0.9398)
			(stroke
				(width 0)
				(type default)
			)
			(fill no)
			(layer "B.Fab")
		)
		(pad "1" smd custom
			(at 0 -0.4445)
			(size 0.1397 0.1397)
			(layers "B.Cu" "B.Mask" "B.Paste")
			(net "Z50_SSD_B1_SMB_DATA_R")
			(options
				(clearance outline)
				(anchor circle)
			)
			(primitives
				(gr_poly
					(pts
						(arc
							(start -0.1778 0.2794)
							(mid -0.249642 0.249642)
							(end -0.2794 0.1778)
						)
						(arc
							(start -0.2794 -0.1778)
							(mid -0.249642 -0.249642)
							(end -0.1778 -0.2794)
						)
						(arc
							(start 0.1778 -0.2794)
							(mid 0.249642 -0.249642)
							(end 0.2794 -0.1778)
						)
						(arc
							(start 0.2794 0.1778)
							(mid 0.249642 0.249642)
							(end 0.1778 0.2794)
						)
					)
					(width 0)
					(fill yes)
				)
			)
		)
		(pad "2" smd custom
			(at 0 0.4445)
			(size 0.1397 0.1397)
			(layers "B.Cu" "B.Mask" "B.Paste")
			(net "P3V3_DPB")
			(options
				(clearance outline)
				(anchor circle)
			)
			(primitives
				(gr_poly
					(pts
						(arc
							(start -0.1778 0.2794)
							(mid -0.249642 0.249642)
							(end -0.2794 0.1778)
						)
						(arc
							(start -0.2794 -0.1778)
							(mid -0.249642 -0.249642)
							(end -0.1778 -0.2794)
						)
						(arc
							(start 0.1778 -0.2794)
							(mid 0.249642 -0.249642)
							(end 0.2794 -0.1778)
						)
						(arc
							(start 0.2794 0.1778)
							(mid 0.249642 0.249642)
							(end 0.1778 0.2794)
						)
					)
					(width 0)
					(fill yes)
				)
			)
		)
	)
	(footprint ""
		(layer "B.Cu")
		(at 68.707 -60.579 180)
		(property "Reference" "R49"
			(at 0 0 0)
			(layer "B.SilkS")
			(hide yes)
			(effects
				(font
					(size 1.27 1.27)
				)
				(justify mirror)
			)
		)
		(property "Value" "47KR2F-GP"
			(at -0.064008 -3.993896 180)
			(unlocked yes)
			(layer "B.Fab")
			(hide yes)
			(effects
				(font
					(size 1.016 1.016)
					(thickness 0.1524)
				)
				(justify mirror)
			)
		)
		(property "Device Type" "R402H16"
			(at -0.064008 -5.517896 180)
			(unlocked yes)
			(layer "B.Fab")
			(hide yes)
			(effects
				(font
					(size 1.016 1.016)
					(thickness 0.1524)
				)
				(justify mirror)
			)
		)
		(duplicate_pad_numbers_are_jumpers no)
		(fp_line
			(start 0.508 -0.9398)
			(end 0.508 0.9398)
			(stroke
				(width 0.1524)
				(type default)
			)
			(layer "B.SilkS")
		)
		(fp_line
			(start -0.508 -0.9398)
			(end 0.508 -0.9398)
			(stroke
				(width 0.1524)
				(type default)
			)
			(layer "B.SilkS")
		)
		(fp_rect
			(start 0.508 0.9398)
			(end -0.508 -0.9398)
			(stroke
				(width 0)
				(type default)
			)
			(fill no)
			(layer "B.CrtYd")
		)
		(fp_rect
			(start 0.508 0.9398)
			(end -0.508 -0.9398)
			(stroke
				(width 0)
				(type default)
			)
			(fill no)
			(layer "B.Fab")
		)
		(pad "1" smd custom
			(at 0 -0.4445)
			(size 0.1397 0.1397)
			(layers "B.Cu" "B.Mask" "B.Paste")
			(net "Z50_SSD_A_ACT#")
			(options
				(clearance outline)
				(anchor circle)
			)
			(primitives
				(gr_poly
					(pts
						(arc
							(start -0.1778 0.2794)
							(mid -0.249642 0.249642)
							(end -0.2794 0.1778)
						)
						(arc
							(start -0.2794 -0.1778)
							(mid -0.249642 -0.249642)
							(end -0.1778 -0.2794)
						)
						(arc
							(start 0.1778 -0.2794)
							(mid 0.249642 -0.249642)
							(end 0.2794 -0.1778)
						)
						(arc
							(start 0.2794 0.1778)
							(mid 0.249642 0.249642)
							(end 0.1778 0.2794)
						)
					)
					(width 0)
					(fill yes)
				)
			)
		)
		(pad "2" smd custom
			(at 0 0.4445)
			(size 0.1397 0.1397)
			(layers "B.Cu" "B.Mask" "B.Paste")
			(net "GND")
			(options
				(clearance outline)
				(anchor circle)
			)
			(primitives
				(gr_poly
					(pts
						(arc
							(start -0.1778 0.2794)
							(mid -0.249642 0.249642)
							(end -0.2794 0.1778)
						)
						(arc
							(start -0.2794 -0.1778)
							(mid -0.249642 -0.249642)
							(end -0.1778 -0.2794)
						)
						(arc
							(start 0.1778 -0.2794)
							(mid 0.249642 -0.249642)
							(end 0.2794 -0.1778)
						)
						(arc
							(start 0.2794 0.1778)
							(mid 0.249642 0.249642)
							(end 0.1778 0.2794)
						)
					)
					(width 0)
					(fill yes)
				)
			)
		)
	)
	(footprint ""
		(layer "B.Cu")
		(at 65.151 -22.479 90)
		(property "Reference" "R42"
			(at 0 0 90)
			(layer "B.SilkS")
			(hide yes)
			(effects
				(font
					(size 1.27 1.27)
				)
				(justify mirror)
			)
		)
		(property "Value" "4K7R2F-GP"
			(at -0.064008 -3.993896 90)
			(unlocked yes)
			(layer "B.Fab")
			(hide yes)
			(effects
				(font
					(size 1.016 1.016)
					(thickness 0.1524)
				)
				(justify mirror)
			)
		)
		(property "Device Type" "R402H16"
			(at -0.064008 -5.517896 90)
			(unlocked yes)
			(layer "B.Fab")
			(hide yes)
			(effects
				(font
					(size 1.016 1.016)
					(thickness 0.1524)
				)
				(justify mirror)
			)
		)
		(duplicate_pad_numbers_are_jumpers no)
		(fp_line
			(start 0.508 -0.9398)
			(end 0.508 0.9398)
			(stroke
				(width 0.1524)
				(type default)
			)
			(layer "B.SilkS")
		)
		(fp_line
			(start -0.508 -0.9398)
			(end 0.508 -0.9398)
			(stroke
				(width 0.1524)
				(type default)
			)
			(layer "B.SilkS")
		)
		(fp_rect
			(start 0.508 0.9398)
			(end -0.508 -0.9398)
			(stroke
				(width 0)
				(type default)
			)
			(fill no)
			(layer "B.CrtYd")
		)
		(fp_rect
			(start 0.508 0.9398)
			(end -0.508 -0.9398)
			(stroke
				(width 0)
				(type default)
			)
			(fill no)
			(layer "B.Fab")
		)
		(pad "1" smd custom
			(at 0 -0.4445 270)
			(size 0.1397 0.1397)
			(layers "B.Cu" "B.Mask" "B.Paste")
			(net "P3V3_PWR")
			(options
				(clearance outline)
				(anchor circle)
			)
			(primitives
				(gr_poly
					(pts
						(arc
							(start -0.1778 0.2794)
							(mid -0.249642 0.249642)
							(end -0.2794 0.1778)
						)
						(arc
							(start -0.2794 -0.1778)
							(mid -0.249642 -0.249642)
							(end -0.1778 -0.2794)
						)
						(arc
							(start 0.1778 -0.2794)
							(mid 0.249642 -0.249642)
							(end 0.2794 -0.1778)
						)
						(arc
							(start 0.2794 0.1778)
							(mid 0.249642 0.249642)
							(end 0.1778 0.2794)
						)
					)
					(width 0)
					(fill yes)
				)
			)
		)
		(pad "2" smd custom
			(at 0 0.4445 270)
			(size 0.1397 0.1397)
			(layers "B.Cu" "B.Mask" "B.Paste")
			(net "Z50_SSD_B1_CLKREQ#")
			(options
				(clearance outline)
				(anchor circle)
			)
			(primitives
				(gr_poly
					(pts
						(arc
							(start -0.1778 0.2794)
							(mid -0.249642 0.249642)
							(end -0.2794 0.1778)
						)
						(arc
							(start -0.2794 -0.1778)
							(mid -0.249642 -0.249642)
							(end -0.1778 -0.2794)
						)
						(arc
							(start 0.1778 -0.2794)
							(mid 0.249642 -0.249642)
							(end 0.2794 -0.1778)
						)
						(arc
							(start 0.2794 0.1778)
							(mid 0.249642 0.249642)
							(end 0.1778 0.2794)
						)
					)
					(width 0)
					(fill yes)
				)
			)
		)
	)
	(footprint ""
		(layer "B.Cu")
		(at 30.226 -78.74)
		(property "Reference" "R60"
			(at 0 0 0)
			(layer "B.SilkS")
			(hide yes)
			(effects
				(font
					(size 1.27 1.27)
				)
				(justify mirror)
			)
		)
		(property "Value" "47KR2F-GP"
			(at -0.064008 -3.993896 0)
			(unlocked yes)
			(layer "B.Fab")
			(hide yes)
			(effects
				(font
					(size 1.016 1.016)
					(thickness 0.1524)
				)
				(justify mirror)
			)
		)
		(property "Device Type" "R402H16"
			(at -0.064008 -5.517896 0)
			(unlocked yes)
			(layer "B.Fab")
			(hide yes)
			(effects
				(font
					(size 1.016 1.016)
					(thickness 0.1524)
				)
				(justify mirror)
			)
		)
		(duplicate_pad_numbers_are_jumpers no)
		(fp_line
			(start -0.508 -0.9398)
			(end 0.508 -0.9398)
			(stroke
				(width 0.1524)
				(type default)
			)
			(layer "B.SilkS")
		)
		(fp_line
			(start 0.508 -0.9398)
			(end 0.508 0.9398)
			(stroke
				(width 0.1524)
				(type default)
			)
			(layer "B.SilkS")
		)
		(fp_rect
			(start 0.508 0.9398)
			(end -0.508 -0.9398)
			(stroke
				(width 0)
				(type default)
			)
			(fill no)
			(layer "B.CrtYd")
		)
		(fp_rect
			(start 0.508 0.9398)
			(end -0.508 -0.9398)
			(stroke
				(width 0)
				(type default)
			)
			(fill no)
			(layer "B.Fab")
		)
		(pad "1" smd custom
			(at 0 -0.4445 180)
			(size 0.1397 0.1397)
			(layers "B.Cu" "B.Mask" "B.Paste")
			(net "Z50_SSD_A1_SMB_CLK_R")
			(options
				(clearance outline)
				(anchor circle)
			)
			(primitives
				(gr_poly
					(pts
						(arc
							(start -0.1778 0.2794)
							(mid -0.249642 0.249642)
							(end -0.2794 0.1778)
						)
						(arc
							(start -0.2794 -0.1778)
							(mid -0.249642 -0.249642)
							(end -0.1778 -0.2794)
						)
						(arc
							(start 0.1778 -0.2794)
							(mid 0.249642 -0.249642)
							(end 0.2794 -0.1778)
						)
						(arc
							(start 0.2794 0.1778)
							(mid 0.249642 0.249642)
							(end 0.1778 0.2794)
						)
					)
					(width 0)
					(fill yes)
				)
			)
		)
		(pad "2" smd custom
			(at 0 0.4445 180)
			(size 0.1397 0.1397)
			(layers "B.Cu" "B.Mask" "B.Paste")
			(net "P3V3_DPB")
			(options
				(clearance outline)
				(anchor circle)
			)
			(primitives
				(gr_poly
					(pts
						(arc
							(start -0.1778 0.2794)
							(mid -0.249642 0.249642)
							(end -0.2794 0.1778)
						)
						(arc
							(start -0.2794 -0.1778)
							(mid -0.249642 -0.249642)
							(end -0.1778 -0.2794)
						)
						(arc
							(start 0.1778 -0.2794)
							(mid 0.249642 -0.249642)
							(end 0.2794 -0.1778)
						)
						(arc
							(start 0.2794 0.1778)
							(mid 0.249642 0.249642)
							(end 0.1778 0.2794)
						)
					)
					(width 0)
					(fill yes)
				)
			)
		)
	)
	(footprint ""
		(layer "B.Cu")
		(at 42.750994 -76.2 180)
		(property "Reference" "PR30"
			(at 0 0 0)
			(layer "B.SilkS")
			(hide yes)
			(effects
				(font
					(size 1.27 1.27)
				)
				(justify mirror)
			)
		)
		(property "Value" "100KR2F-L1-GP"
			(at -0.064008 -3.993896 180)
			(unlocked yes)
			(layer "B.Fab")
			(hide yes)
			(effects
				(font
					(size 1.016 1.016)
					(thickness 0.1524)
				)
				(justify mirror)
			)
		)
		(property "Device Type" "R402H16"
			(at -0.064008 -5.517896 180)
			(unlocked yes)
			(layer "B.Fab")
			(hide yes)
			(effects
				(font
					(size 1.016 1.016)
					(thickness 0.1524)
				)
				(justify mirror)
			)
		)
		(duplicate_pad_numbers_are_jumpers no)
		(fp_line
			(start 0.508 -0.9398)
			(end 0.508 0.9398)
			(stroke
				(width 0.1524)
				(type default)
			)
			(layer "B.SilkS")
		)
		(fp_line
			(start -0.508 -0.9398)
			(end 0.508 -0.9398)
			(stroke
				(width 0.1524)
				(type default)
			)
			(layer "B.SilkS")
		)
		(fp_rect
			(start 0.508 0.9398)
			(end -0.508 -0.9398)
			(stroke
				(width 0)
				(type default)
			)
			(fill no)
			(layer "B.CrtYd")
		)
		(fp_rect
			(start 0.508 0.9398)
			(end -0.508 -0.9398)
			(stroke
				(width 0)
				(type default)
			)
			(fill no)
			(layer "B.Fab")
		)
		(pad "1" smd custom
			(at 0 -0.4445)
			(size 0.1397 0.1397)
			(layers "B.Cu" "B.Mask" "B.Paste")
			(net "AGND_P3V3_DEV")
			(options
				(clearance outline)
				(anchor circle)
			)
			(primitives
				(gr_poly
					(pts
						(arc
							(start -0.1778 0.2794)
							(mid -0.249642 0.249642)
							(end -0.2794 0.1778)
						)
						(arc
							(start -0.2794 -0.1778)
							(mid -0.249642 -0.249642)
							(end -0.1778 -0.2794)
						)
						(arc
							(start 0.1778 -0.2794)
							(mid 0.249642 -0.249642)
							(end 0.2794 -0.1778)
						)
						(arc
							(start 0.2794 0.1778)
							(mid 0.249642 0.249642)
							(end 0.1778 0.2794)
						)
					)
					(width 0)
					(fill yes)
				)
			)
		)
		(pad "2" smd custom
			(at 0 0.4445)
			(size 0.1397 0.1397)
			(layers "B.Cu" "B.Mask" "B.Paste")
			(net "P3V3_DEV_MODE")
			(options
				(clearance outline)
				(anchor circle)
			)
			(primitives
				(gr_poly
					(pts
						(arc
							(start -0.1778 0.2794)
							(mid -0.249642 0.249642)
							(end -0.2794 0.1778)
						)
						(arc
							(start -0.2794 -0.1778)
							(mid -0.249642 -0.249642)
							(end -0.1778 -0.2794)
						)
						(arc
							(start 0.1778 -0.2794)
							(mid 0.249642 -0.249642)
							(end 0.2794 -0.1778)
						)
						(arc
							(start 0.2794 0.1778)
							(mid 0.249642 0.249642)
							(end 0.1778 0.2794)
						)
					)
					(width 0)
					(fill yes)
				)
			)
		)
	)
	(footprint ""
		(layer "B.Cu")
		(at 28.956 -71.755 180)
		(property "Reference" "R34"
			(at 0 0 0)
			(layer "B.SilkS")
			(hide yes)
			(effects
				(font
					(size 1.27 1.27)
				)
				(justify mirror)
			)
		)
		(property "Value" "47KR2F-GP"
			(at -0.064008 -3.993896 180)
			(unlocked yes)
			(layer "B.Fab")
			(hide yes)
			(effects
				(font
					(size 1.016 1.016)
					(thickness 0.1524)
				)
				(justify mirror)
			)
		)
		(property "Device Type" "R402H16"
			(at -0.064008 -5.517896 180)
			(unlocked yes)
			(layer "B.Fab")
			(hide yes)
			(effects
				(font
					(size 1.016 1.016)
					(thickness 0.1524)
				)
				(justify mirror)
			)
		)
		(duplicate_pad_numbers_are_jumpers no)
		(fp_line
			(start 0.508 -0.9398)
			(end 0.508 0.9398)
			(stroke
				(width 0.1524)
				(type default)
			)
			(layer "B.SilkS")
		)
		(fp_line
			(start -0.508 -0.9398)
			(end 0.508 -0.9398)
			(stroke
				(width 0.1524)
				(type default)
			)
			(layer "B.SilkS")
		)
		(fp_rect
			(start 0.508 0.9398)
			(end -0.508 -0.9398)
			(stroke
				(width 0)
				(type default)
			)
			(fill no)
			(layer "B.CrtYd")
		)
		(fp_rect
			(start 0.508 0.9398)
			(end -0.508 -0.9398)
			(stroke
				(width 0)
				(type default)
			)
			(fill no)
			(layer "B.Fab")
		)
		(pad "1" smd custom
			(at 0 -0.4445)
			(size 0.1397 0.1397)
			(layers "B.Cu" "B.Mask" "B.Paste")
			(net "Z50_SSD_B1_SMB_DATA")
			(options
				(clearance outline)
				(anchor circle)
			)
			(primitives
				(gr_poly
					(pts
						(arc
							(start -0.1778 0.2794)
							(mid -0.249642 0.249642)
							(end -0.2794 0.1778)
						)
						(arc
							(start -0.2794 -0.1778)
							(mid -0.249642 -0.249642)
							(end -0.1778 -0.2794)
						)
						(arc
							(start 0.1778 -0.2794)
							(mid 0.249642 -0.249642)
							(end 0.2794 -0.1778)
						)
						(arc
							(start 0.2794 0.1778)
							(mid 0.249642 0.249642)
							(end 0.1778 0.2794)
						)
					)
					(width 0)
					(fill yes)
				)
			)
		)
		(pad "2" smd custom
			(at 0 0.4445)
			(size 0.1397 0.1397)
			(layers "B.Cu" "B.Mask" "B.Paste")
			(net "P1V8_PWR")
			(options
				(clearance outline)
				(anchor circle)
			)
			(primitives
				(gr_poly
					(pts
						(arc
							(start -0.1778 0.2794)
							(mid -0.249642 0.249642)
							(end -0.2794 0.1778)
						)
						(arc
							(start -0.2794 -0.1778)
							(mid -0.249642 -0.249642)
							(end -0.1778 -0.2794)
						)
						(arc
							(start 0.1778 -0.2794)
							(mid 0.249642 -0.249642)
							(end 0.2794 -0.1778)
						)
						(arc
							(start 0.2794 0.1778)
							(mid 0.249642 0.249642)
							(end 0.1778 0.2794)
						)
					)
					(width 0)
					(fill yes)
				)
			)
		)
	)
	(footprint ""
		(layer "B.Cu")
		(at 62.738 -39.751 90)
		(property "Reference" "R9"
			(at 0 0 90)
			(layer "B.SilkS")
			(hide yes)
			(effects
				(font
					(size 1.27 1.27)
				)
				(justify mirror)
			)
		)
		(property "Value" "0R2J-2-GP"
			(at -0.064008 -3.993896 90)
			(unlocked yes)
			(layer "B.Fab")
			(hide yes)
			(effects
				(font
					(size 1.016 1.016)
					(thickness 0.1524)
				)
				(justify mirror)
			)
		)
		(property "Device Type" "R402H16"
			(at -0.064008 -5.517896 90)
			(unlocked yes)
			(layer "B.Fab")
			(hide yes)
			(effects
				(font
					(size 1.016 1.016)
					(thickness 0.1524)
				)
				(justify mirror)
			)
		)
		(duplicate_pad_numbers_are_jumpers no)
		(fp_line
			(start 0.508 -0.9398)
			(end 0.508 0.9398)
			(stroke
				(width 0.1524)
				(type default)
			)
			(layer "B.SilkS")
		)
		(fp_line
			(start -0.508 -0.9398)
			(end 0.508 -0.9398)
			(stroke
				(width 0.1524)
				(type default)
			)
			(layer "B.SilkS")
		)
		(fp_rect
			(start 0.508 0.9398)
			(end -0.508 -0.9398)
			(stroke
				(width 0)
				(type default)
			)
			(fill no)
			(layer "B.CrtYd")
		)
		(fp_rect
			(start 0.508 0.9398)
			(end -0.508 -0.9398)
			(stroke
				(width 0)
				(type default)
			)
			(fill no)
			(layer "B.Fab")
		)
		(pad "1" smd custom
			(at 0 -0.4445 270)
			(size 0.1397 0.1397)
			(layers "B.Cu" "B.Mask" "B.Paste")
			(net "Z50_SMB_CLK")
			(options
				(clearance outline)
				(anchor circle)
			)
			(primitives
				(gr_poly
					(pts
						(arc
							(start -0.1778 0.2794)
							(mid -0.249642 0.249642)
							(end -0.2794 0.1778)
						)
						(arc
							(start -0.2794 -0.1778)
							(mid -0.249642 -0.249642)
							(end -0.1778 -0.2794)
						)
						(arc
							(start 0.1778 -0.2794)
							(mid 0.249642 -0.249642)
							(end 0.2794 -0.1778)
						)
						(arc
							(start 0.2794 0.1778)
							(mid 0.249642 0.249642)
							(end 0.1778 0.2794)
						)
					)
					(width 0)
					(fill yes)
				)
			)
		)
		(pad "2" smd custom
			(at 0 0.4445 270)
			(size 0.1397 0.1397)
			(layers "B.Cu" "B.Mask" "B.Paste")
			(net "Z50_TEMP_1_CLK")
			(options
				(clearance outline)
				(anchor circle)
			)
			(primitives
				(gr_poly
					(pts
						(arc
							(start -0.1778 0.2794)
							(mid -0.249642 0.249642)
							(end -0.2794 0.1778)
						)
						(arc
							(start -0.2794 -0.1778)
							(mid -0.249642 -0.249642)
							(end -0.1778 -0.2794)
						)
						(arc
							(start 0.1778 -0.2794)
							(mid 0.249642 -0.249642)
							(end 0.2794 -0.1778)
						)
						(arc
							(start 0.2794 0.1778)
							(mid 0.249642 0.249642)
							(end 0.1778 0.2794)
						)
					)
					(width 0)
					(fill yes)
				)
			)
		)
	)
)
